FILE_TYPE = CONNECTIVITY;
{Allegro Design Entry HDL 16.6-p007 (v16-6-112F) 10/10/2012}
"PAGE_NUMBER" = 264;
0"NC";
END.
